(kicad_pcb
	(version 20260206)
	(generator "pcbnew")
	(generator_version "10.0")
	(general
		(thickness 1.6)
		(legacy_teardrops no)
	)
	(paper "A4")
	(title_block
		(title "01162023_DA0F0TEBIF0_F0T_Expander_BD_F_brd_V02_OCP.brd")
		(comment 1 "Grand Teton / footprints 2091-2097 of 9728")
	)
	(layers
		(0 "F.Cu" signal "TOP")
		(4 "In1.Cu" signal "GND")
		(6 "In2.Cu" signal "VCC")
		(8 "In3.Cu" signal "VCC1")
		(10 "In4.Cu" signal "GND1")
		(12 "In5.Cu" signal "IN1")
		(14 "In6.Cu" signal "GND2")
		(16 "In7.Cu" signal "IN2")
		(18 "In8.Cu" signal "GND3")
		(20 "In9.Cu" signal "IN3")
		(22 "In10.Cu" signal "GND4")
		(24 "In11.Cu" signal "IN4")
		(26 "In12.Cu" signal "GND5")
		(28 "In13.Cu" signal "IN5")
		(30 "In14.Cu" signal "GND6")
		(32 "In15.Cu" signal "IN6")
		(34 "In16.Cu" signal "GND7")
		(2 "B.Cu" signal "BOTTOM")
		(9 "F.Adhes" user "F.Adhesive")
		(11 "B.Adhes" user "B.Adhesive")
		(13 "F.Paste" user "Package Geometry/Pastemask Top")
		(15 "B.Paste" user "Package Geometry/Pastemask Bottom")
		(5 "F.SilkS" user "Ref Des/Silkscreen Top")
		(7 "B.SilkS" user "Ref Des/Silkscreen Bottom")
		(1 "F.Mask" user "Board Geometry/Soldermask Top")
		(3 "B.Mask" user "Board Geometry/Soldermask Bottom")
		(17 "Dwgs.User" user "User.Drawings")
		(19 "Cmts.User" user "User.Comments")
		(21 "Eco1.User" user "User.Eco1")
		(23 "Eco2.User" user "User.Eco2")
		(25 "Edge.Cuts" user "Board Geometry/Outline")
		(27 "Margin" user)
		(31 "F.CrtYd" user "Package Geometry/Place Bound Top")
		(29 "B.CrtYd" user "Package Geometry/Place Bound Bottom")
		(35 "F.Fab" user "Ref Des/Assembly Top")
		(33 "B.Fab" user "Ref Des/Assembly Bottom")
	)
	(footprint ""
		(layer "F.Cu")
		(at 138.985244 -93.528642 180)
		(property "Reference" "R1570"
			(at 0 0 180)
			(layer "F.SilkS")
			(hide yes)
			(effects
				(font
					(size 1.27 1.27)
				)
			)
		)
		(property "Value" ""
			(at 0 0 180)
			(layer "F.Fab")
			(effects
				(font
					(size 1.27 1.27)
				)
			)
		)
		(duplicate_pad_numbers_are_jumpers no)
		(fp_line
			(start 0.7874 0.4064)
			(end -0.7874 0.4064)
			(stroke
				(width 0.1524)
				(type default)
			)
			(layer "F.SilkS")
		)
		(fp_line
			(start 0.7874 -0.4064)
			(end 0.7874 0.4064)
			(stroke
				(width 0.1524)
				(type default)
			)
			(layer "F.SilkS")
		)
		(fp_line
			(start -0.7874 0.4064)
			(end -0.7874 -0.4064)
			(stroke
				(width 0.1524)
				(type default)
			)
			(layer "F.SilkS")
		)
		(fp_line
			(start -0.7874 -0.4064)
			(end 0.7874 -0.4064)
			(stroke
				(width 0.1524)
				(type default)
			)
			(layer "F.SilkS")
		)
		(fp_line
			(start 0.67945 0.3048)
			(end 0.120396 0.3048)
			(stroke
				(width 0.1)
				(type default)
			)
			(layer "F.Fab")
		)
		(fp_line
			(start 0.67945 -0.3048)
			(end 0.67945 0.3048)
			(stroke
				(width 0.1)
				(type default)
			)
			(layer "F.Fab")
		)
		(fp_line
			(start 0.12065 -0.2794)
			(end 0.12065 -0.3048)
			(stroke
				(width 0.1)
				(type default)
			)
			(layer "F.Fab")
		)
		(fp_line
			(start 0.12065 -0.3048)
			(end 0.67945 -0.3048)
			(stroke
				(width 0.1)
				(type default)
			)
			(layer "F.Fab")
		)
		(fp_line
			(start 0.120396 0.3048)
			(end 0.120396 0.2794)
			(stroke
				(width 0.1)
				(type default)
			)
			(layer "F.Fab")
		)
		(fp_line
			(start 0.120396 0.2794)
			(end -0.12065 0.2794)
			(stroke
				(width 0.1)
				(type default)
			)
			(layer "F.Fab")
		)
		(fp_line
			(start -0.12065 0.3048)
			(end -0.67945 0.3048)
			(stroke
				(width 0.1)
				(type default)
			)
			(layer "F.Fab")
		)
		(fp_line
			(start -0.12065 0.2794)
			(end -0.12065 0.3048)
			(stroke
				(width 0.1)
				(type default)
			)
			(layer "F.Fab")
		)
		(fp_line
			(start -0.12065 -0.2794)
			(end 0.12065 -0.2794)
			(stroke
				(width 0.1)
				(type default)
			)
			(layer "F.Fab")
		)
		(fp_line
			(start -0.12065 -0.305054)
			(end -0.12065 -0.2794)
			(stroke
				(width 0.1)
				(type default)
			)
			(layer "F.Fab")
		)
		(fp_line
			(start -0.67945 0.3048)
			(end -0.67945 -0.305054)
			(stroke
				(width 0.1)
				(type default)
			)
			(layer "F.Fab")
		)
		(fp_line
			(start -0.67945 -0.305054)
			(end -0.12065 -0.305054)
			(stroke
				(width 0.1)
				(type default)
			)
			(layer "F.Fab")
		)
		(pad "1" smd circle
			(at -0.40005 0 180)
			(size 0 0)
			(layers "F.Cu" "F.Mask" "F.Paste")
			(net "P3V3_AUX")
		)
		(pad "2" smd circle
			(at 0.40005 0 180)
			(size 0 0)
			(layers "F.Cu" "F.Mask" "F.Paste")
			(net "SMB_BIC_I2C9_MUX0_SSD6_R_SCL")
		)
	)
	(footprint ""
		(layer "F.Cu")
		(at 450.230494 -119.77624 180)
		(property "Reference" "R6047"
			(at 0 0 180)
			(layer "F.SilkS")
			(hide yes)
			(effects
				(font
					(size 1.27 1.27)
				)
			)
		)
		(property "Value" ""
			(at 0 0 180)
			(layer "F.Fab")
			(effects
				(font
					(size 1.27 1.27)
				)
			)
		)
		(duplicate_pad_numbers_are_jumpers no)
		(fp_line
			(start 0.7874 0.4064)
			(end -0.7874 0.4064)
			(stroke
				(width 0.1524)
				(type default)
			)
			(layer "F.SilkS")
		)
		(fp_line
			(start 0.7874 -0.4064)
			(end 0.7874 0.4064)
			(stroke
				(width 0.1524)
				(type default)
			)
			(layer "F.SilkS")
		)
		(fp_line
			(start -0.7874 0.4064)
			(end -0.7874 -0.4064)
			(stroke
				(width 0.1524)
				(type default)
			)
			(layer "F.SilkS")
		)
		(fp_line
			(start -0.7874 -0.4064)
			(end 0.7874 -0.4064)
			(stroke
				(width 0.1524)
				(type default)
			)
			(layer "F.SilkS")
		)
		(fp_line
			(start 0.67945 0.3048)
			(end 0.120396 0.3048)
			(stroke
				(width 0.1)
				(type default)
			)
			(layer "F.Fab")
		)
		(fp_line
			(start 0.67945 -0.3048)
			(end 0.67945 0.3048)
			(stroke
				(width 0.1)
				(type default)
			)
			(layer "F.Fab")
		)
		(fp_line
			(start 0.12065 -0.2794)
			(end 0.12065 -0.3048)
			(stroke
				(width 0.1)
				(type default)
			)
			(layer "F.Fab")
		)
		(fp_line
			(start 0.12065 -0.3048)
			(end 0.67945 -0.3048)
			(stroke
				(width 0.1)
				(type default)
			)
			(layer "F.Fab")
		)
		(fp_line
			(start 0.120396 0.3048)
			(end 0.120396 0.2794)
			(stroke
				(width 0.1)
				(type default)
			)
			(layer "F.Fab")
		)
		(fp_line
			(start 0.120396 0.2794)
			(end -0.12065 0.2794)
			(stroke
				(width 0.1)
				(type default)
			)
			(layer "F.Fab")
		)
		(fp_line
			(start -0.12065 0.3048)
			(end -0.67945 0.3048)
			(stroke
				(width 0.1)
				(type default)
			)
			(layer "F.Fab")
		)
		(fp_line
			(start -0.12065 0.2794)
			(end -0.12065 0.3048)
			(stroke
				(width 0.1)
				(type default)
			)
			(layer "F.Fab")
		)
		(fp_line
			(start -0.12065 -0.2794)
			(end 0.12065 -0.2794)
			(stroke
				(width 0.1)
				(type default)
			)
			(layer "F.Fab")
		)
		(fp_line
			(start -0.12065 -0.305054)
			(end -0.12065 -0.2794)
			(stroke
				(width 0.1)
				(type default)
			)
			(layer "F.Fab")
		)
		(fp_line
			(start -0.67945 0.3048)
			(end -0.67945 -0.305054)
			(stroke
				(width 0.1)
				(type default)
			)
			(layer "F.Fab")
		)
		(fp_line
			(start -0.67945 -0.305054)
			(end -0.12065 -0.305054)
			(stroke
				(width 0.1)
				(type default)
			)
			(layer "F.Fab")
		)
		(pad "1" smd circle
			(at -0.40005 0 180)
			(size 0 0)
			(layers "F.Cu" "F.Mask" "F.Paste")
			(net "PWRGD_P3V3_NIC7_D")
		)
		(pad "2" smd circle
			(at 0.40005 0 180)
			(size 0 0)
			(layers "F.Cu" "F.Mask" "F.Paste")
			(net "PWRGD_P3V3_NIC7_R")
		)
	)
	(footprint ""
		(layer "F.Cu")
		(at 50.396648 -343.952322 90)
		(property "Reference" "C2180"
			(at 0 0 90)
			(layer "F.SilkS")
			(hide yes)
			(effects
				(font
					(size 1.27 1.27)
				)
			)
		)
		(property "Value" ""
			(at 0 0 90)
			(layer "F.Fab")
			(effects
				(font
					(size 1.27 1.27)
				)
			)
		)
		(duplicate_pad_numbers_are_jumpers no)
		(fp_line
			(start 0.299974 -0.150114)
			(end 0.299974 0.150114)
			(stroke
				(width 0.1)
				(type default)
			)
			(layer "F.Fab")
		)
		(fp_line
			(start -0.299974 -0.150114)
			(end 0.299974 -0.150114)
			(stroke
				(width 0.1)
				(type default)
			)
			(layer "F.Fab")
		)
		(fp_line
			(start 0.299974 0.150114)
			(end -0.299974 0.150114)
			(stroke
				(width 0.1)
				(type default)
			)
			(layer "F.Fab")
		)
		(fp_line
			(start -0.299974 0.150114)
			(end -0.299974 -0.150114)
			(stroke
				(width 0.1)
				(type default)
			)
			(layer "F.Fab")
		)
		(pad "1" smd rect
			(at -0.2667 0 90)
			(size 0.3048 0.381)
			(layers "F.Cu" "F.Mask" "F.Paste")
			(net "P5E_PEX0_STN4_TX_DP<65>")
		)
		(pad "2" smd rect
			(at 0.2667 0 90)
			(size 0.3048 0.381)
			(layers "F.Cu" "F.Mask" "F.Paste")
			(net "P5E_PEX0_STN4_TX_C_DP<65>")
		)
	)
	(footprint ""
		(layer "F.Cu")
		(at 236.573822 -27.006296 -90)
		(property "Reference" "PC944"
			(at 0 0 270)
			(layer "F.SilkS")
			(hide yes)
			(effects
				(font
					(size 1.27 1.27)
				)
			)
		)
		(property "Value" ""
			(at 0 0 270)
			(layer "F.Fab")
			(effects
				(font
					(size 1.27 1.27)
				)
			)
		)
		(duplicate_pad_numbers_are_jumpers no)
		(fp_line
			(start -0.7874 0.4064)
			(end -0.7874 -0.4064)
			(stroke
				(width 0.1524)
				(type default)
			)
			(layer "F.SilkS")
		)
		(fp_line
			(start 0.7874 0.4064)
			(end -0.7874 0.4064)
			(stroke
				(width 0.1524)
				(type default)
			)
			(layer "F.SilkS")
		)
		(fp_line
			(start -0.7874 -0.4064)
			(end 0.7874 -0.4064)
			(stroke
				(width 0.1524)
				(type default)
			)
			(layer "F.SilkS")
		)
		(fp_line
			(start 0.7874 -0.4064)
			(end 0.7874 0.4064)
			(stroke
				(width 0.1524)
				(type default)
			)
			(layer "F.SilkS")
		)
		(fp_line
			(start -0.67945 0.3048)
			(end -0.67945 -0.305054)
			(stroke
				(width 0.1)
				(type default)
			)
			(layer "F.Fab")
		)
		(fp_line
			(start -0.12065 0.3048)
			(end -0.67945 0.3048)
			(stroke
				(width 0.1)
				(type default)
			)
			(layer "F.Fab")
		)
		(fp_line
			(start 0.120396 0.3048)
			(end 0.120396 0.2794)
			(stroke
				(width 0.1)
				(type default)
			)
			(layer "F.Fab")
		)
		(fp_line
			(start 0.67945 0.3048)
			(end 0.120396 0.3048)
			(stroke
				(width 0.1)
				(type default)
			)
			(layer "F.Fab")
		)
		(fp_line
			(start -0.12065 0.2794)
			(end -0.12065 0.3048)
			(stroke
				(width 0.1)
				(type default)
			)
			(layer "F.Fab")
		)
		(fp_line
			(start 0.120396 0.2794)
			(end -0.12065 0.2794)
			(stroke
				(width 0.1)
				(type default)
			)
			(layer "F.Fab")
		)
		(fp_line
			(start -0.12065 -0.2794)
			(end 0.12065 -0.2794)
			(stroke
				(width 0.1)
				(type default)
			)
			(layer "F.Fab")
		)
		(fp_line
			(start 0.12065 -0.2794)
			(end 0.12065 -0.3048)
			(stroke
				(width 0.1)
				(type default)
			)
			(layer "F.Fab")
		)
		(fp_line
			(start 0.12065 -0.3048)
			(end 0.67945 -0.3048)
			(stroke
				(width 0.1)
				(type default)
			)
			(layer "F.Fab")
		)
		(fp_line
			(start 0.67945 -0.3048)
			(end 0.67945 0.3048)
			(stroke
				(width 0.1)
				(type default)
			)
			(layer "F.Fab")
		)
		(fp_line
			(start -0.67945 -0.305054)
			(end -0.12065 -0.305054)
			(stroke
				(width 0.1)
				(type default)
			)
			(layer "F.Fab")
		)
		(fp_line
			(start -0.12065 -0.305054)
			(end -0.12065 -0.2794)
			(stroke
				(width 0.1)
				(type default)
			)
			(layer "F.Fab")
		)
		(pad "1" smd circle
			(at -0.40005 0 270)
			(size 0 0)
			(layers "F.Cu" "F.Mask" "F.Paste")
			(net "P3V3_SSD8_CO_MODE")
		)
		(pad "2" smd circle
			(at 0.40005 0 270)
			(size 0 0)
			(layers "F.Cu" "F.Mask" "F.Paste")
			(net "GND")
		)
	)
	(footprint ""
		(layer "F.Cu")
		(at 350.139762 -237.69828 90)
		(property "Reference" "R6835"
			(at 0 0 90)
			(layer "F.SilkS")
			(hide yes)
			(effects
				(font
					(size 1.27 1.27)
				)
			)
		)
		(property "Value" ""
			(at 0 0 90)
			(layer "F.Fab")
			(effects
				(font
					(size 1.27 1.27)
				)
			)
		)
		(duplicate_pad_numbers_are_jumpers no)
		(fp_line
			(start 0.7874 -0.4064)
			(end 0.7874 0.4064)
			(stroke
				(width 0.1524)
				(type default)
			)
			(layer "F.SilkS")
		)
		(fp_line
			(start -0.7874 -0.4064)
			(end 0.7874 -0.4064)
			(stroke
				(width 0.1524)
				(type default)
			)
			(layer "F.SilkS")
		)
		(fp_line
			(start 0.7874 0.4064)
			(end -0.7874 0.4064)
			(stroke
				(width 0.1524)
				(type default)
			)
			(layer "F.SilkS")
		)
		(fp_line
			(start -0.7874 0.4064)
			(end -0.7874 -0.4064)
			(stroke
				(width 0.1524)
				(type default)
			)
			(layer "F.SilkS")
		)
		(fp_line
			(start -0.12065 -0.305054)
			(end -0.12065 -0.2794)
			(stroke
				(width 0.1)
				(type default)
			)
			(layer "F.Fab")
		)
		(fp_line
			(start -0.67945 -0.305054)
			(end -0.12065 -0.305054)
			(stroke
				(width 0.1)
				(type default)
			)
			(layer "F.Fab")
		)
		(fp_line
			(start 0.67945 -0.3048)
			(end 0.67945 0.3048)
			(stroke
				(width 0.1)
				(type default)
			)
			(layer "F.Fab")
		)
		(fp_line
			(start 0.12065 -0.3048)
			(end 0.67945 -0.3048)
			(stroke
				(width 0.1)
				(type default)
			)
			(layer "F.Fab")
		)
		(fp_line
			(start 0.12065 -0.2794)
			(end 0.12065 -0.3048)
			(stroke
				(width 0.1)
				(type default)
			)
			(layer "F.Fab")
		)
		(fp_line
			(start -0.12065 -0.2794)
			(end 0.12065 -0.2794)
			(stroke
				(width 0.1)
				(type default)
			)
			(layer "F.Fab")
		)
		(fp_line
			(start 0.120396 0.2794)
			(end -0.12065 0.2794)
			(stroke
				(width 0.1)
				(type default)
			)
			(layer "F.Fab")
		)
		(fp_line
			(start -0.12065 0.2794)
			(end -0.12065 0.3048)
			(stroke
				(width 0.1)
				(type default)
			)
			(layer "F.Fab")
		)
		(fp_line
			(start 0.67945 0.3048)
			(end 0.120396 0.3048)
			(stroke
				(width 0.1)
				(type default)
			)
			(layer "F.Fab")
		)
		(fp_line
			(start 0.120396 0.3048)
			(end 0.120396 0.2794)
			(stroke
				(width 0.1)
				(type default)
			)
			(layer "F.Fab")
		)
		(fp_line
			(start -0.12065 0.3048)
			(end -0.67945 0.3048)
			(stroke
				(width 0.1)
				(type default)
			)
			(layer "F.Fab")
		)
		(fp_line
			(start -0.67945 0.3048)
			(end -0.67945 -0.305054)
			(stroke
				(width 0.1)
				(type default)
			)
			(layer "F.Fab")
		)
		(pad "1" smd circle
			(at -0.40005 0 90)
			(size 0 0)
			(layers "F.Cu" "F.Mask" "F.Paste")
			(net "SSD6_PWR_EN_R")
		)
		(pad "2" smd circle
			(at 0.40005 0 90)
			(size 0 0)
			(layers "F.Cu" "F.Mask" "F.Paste")
			(net "GND")
		)
	)
	(footprint ""
		(layer "F.Cu")
		(at 102.734872 -215.055958 180)
		(property "Reference" "PC284"
			(at 0 0 180)
			(layer "F.SilkS")
			(hide yes)
			(effects
				(font
					(size 1.27 1.27)
				)
			)
		)
		(property "Value" ""
			(at 0 0 180)
			(layer "F.Fab")
			(effects
				(font
					(size 1.27 1.27)
				)
			)
		)
		(duplicate_pad_numbers_are_jumpers no)
		(fp_line
			(start 1.524 0.762)
			(end -1.524 0.762)
			(stroke
				(width 0.1524)
				(type default)
			)
			(layer "F.SilkS")
		)
		(fp_line
			(start 1.524 -0.762)
			(end 1.524 0.762)
			(stroke
				(width 0.1524)
				(type default)
			)
			(layer "F.SilkS")
		)
		(fp_line
			(start -1.524 0.762)
			(end -1.524 -0.762)
			(stroke
				(width 0.1524)
				(type default)
			)
			(layer "F.SilkS")
		)
		(fp_line
			(start -1.524 -0.762)
			(end 1.524 -0.762)
			(stroke
				(width 0.1524)
				(type default)
			)
			(layer "F.SilkS")
		)
		(fp_line
			(start 1.1049 0.724916)
			(end 1.1049 -0.724916)
			(stroke
				(width 0.1)
				(type default)
			)
			(layer "F.Fab")
		)
		(fp_line
			(start 1.1049 -0.724916)
			(end -1.1049 -0.724916)
			(stroke
				(width 0.1)
				(type default)
			)
			(layer "F.Fab")
		)
		(fp_line
			(start -1.1049 0.724916)
			(end 1.1049 0.724916)
			(stroke
				(width 0.1)
				(type default)
			)
			(layer "F.Fab")
		)
		(fp_line
			(start -1.1049 -0.724916)
			(end -1.1049 0.724916)
			(stroke
				(width 0.1)
				(type default)
			)
			(layer "F.Fab")
		)
		(pad "1" smd rect
			(at -0.889 0)
			(size 1.016 1.27)
			(layers "F.Cu" "F.Mask" "F.Paste")
			(net "SW_P12V_P1V8_PEX_FLT")
		)
		(pad "2" smd rect
			(at 0.889 0)
			(size 1.016 1.27)
			(layers "F.Cu" "F.Mask" "F.Paste")
			(net "GND")
		)
	)
	(footprint ""
		(layer "F.Cu")
		(at 36.638484 -120.113298)
		(property "Reference" "C48"
			(at 0 0 0)
			(layer "F.SilkS")
			(hide yes)
			(effects
				(font
					(size 1.27 1.27)
				)
			)
		)
		(property "Value" ""
			(at 0 0 0)
			(layer "F.Fab")
			(effects
				(font
					(size 1.27 1.27)
				)
			)
		)
		(duplicate_pad_numbers_are_jumpers no)
		(fp_line
			(start -0.299974 -0.150114)
			(end 0.299974 -0.150114)
			(stroke
				(width 0.1)
				(type default)
			)
			(layer "F.Fab")
		)
		(fp_line
			(start -0.299974 0.150114)
			(end -0.299974 -0.150114)
			(stroke
				(width 0.1)
				(type default)
			)
			(layer "F.Fab")
		)
		(fp_line
			(start 0.299974 -0.150114)
			(end 0.299974 0.150114)
			(stroke
				(width 0.1)
				(type default)
			)
			(layer "F.Fab")
		)
		(fp_line
			(start 0.299974 0.150114)
			(end -0.299974 0.150114)
			(stroke
				(width 0.1)
				(type default)
			)
			(layer "F.Fab")
		)
		(pad "1" smd rect
			(at -0.2667 0)
			(size 0.3048 0.381)
			(layers "F.Cu" "F.Mask" "F.Paste")
			(net "P5E_PEX0_STN1_TX_DN<24>")
		)
		(pad "2" smd rect
			(at 0.2667 0)
			(size 0.3048 0.381)
			(layers "F.Cu" "F.Mask" "F.Paste")
			(net "P5E_PEX0_STN1_TX_C_DN<24>")
		)
	)
)
